#ISCELL
  pure_quanta quanta_title_block_c *
  *
#CELL
  pure_quanta pt5161lrs *
  page395_i1
#ISCELL
  standard tap *
  page395_i10
#ISCELL
  standard tap *
  page395_i11
#ISCELL
  standard tap *
  page395_i12
#ISCELL
  standard tap *
  page395_i13
#ISCELL
  standard tap *
  page395_i14
#ISCELL
  standard tap *
  page395_i15
#ISCELL
  standard tap *
  page395_i16
#ISCELL
  standard tap *
  page395_i17
#ISCELL
  standard offpage *
  page395_i18
#ISCELL
  standard offpage *
  page395_i19
#ISCELL
  standard tap *
  page395_i2
#ISCELL
  standard tap *
  page395_i20
#ISCELL
  standard tap *
  page395_i21
#ISCELL
  standard tap *
  page395_i22
#ISCELL
  standard tap *
  page395_i23
#ISCELL
  standard tap *
  page395_i24
#ISCELL
  standard tap *
  page395_i25
#ISCELL
  standard tap *
  page395_i26
#ISCELL
  standard tap *
  page395_i27
#ISCELL
  standard tap *
  page395_i28
#ISCELL
  standard tap *
  page395_i29
#ISCELL
  standard tap *
  page395_i3
#ISCELL
  standard tap *
  page395_i30
#ISCELL
  standard tap *
  page395_i31
#ISCELL
  standard tap *
  page395_i32
#ISCELL
  standard tap *
  page395_i33
#ISCELL
  standard tap *
  page395_i34
#ISCELL
  standard tap *
  page395_i35
#ISCELL
  standard offpage *
  page395_i36
#ISCELL
  standard offpage *
  page395_i37
#CELL
  pure_quanta pt5161lrs *
  page395_i38
#ISCELL
  standard tap *
  page395_i4
#ISCELL
  standard tap *
  page395_i5
#ISCELL
  standard tap *
  page395_i6
#ISCELL
  standard tap *
  page395_i7
#ISCELL
  standard tap *
  page395_i8
#ISCELL
  standard tap *
  page395_i9
